# S9S_MB_2U (Grand Teton) — schematic netlist excerpt (pin names and nets, part order shuffled) for the footprints in the layout excerpt that follows; sources: Cadence DE-HDL packaged netlist, KiCad conversion of 03242023_DA0F0TMBIJ0_F0T_Motherboard_J_brd_V01_OCP.brd

R986  Q_RES  33.2 1% CHIP  pkg 0402LF  page 222 : A = FM_PVCCFA_EHV_CPU1_R_EN ; B = FM_PVCCFA_EHV_CPU1_EN
R893  Q_RES  33.2 1% CHIP  pkg 0402LF  page 114 : A = PWRGD_CHA_CPU1_DIMM1 ; B = PWRGD_FAIL_CPU1_AB

(kicad_pcb
	(version 20260206)
	(generator "pcbnew")
	(generator_version "10.0")
	(general
		(thickness 1.6)
		(legacy_teardrops no)
	)
	(paper "A4")
	(title_block
		(title "03242023_DA0F0TMBIJ0_F0T_Motherboard_J_brd_V01_OCP.brd")
		(comment 1 "Grand Teton / footprints 5290-5291 of 6105")
	)
	(layers
		(0 "F.Cu" signal "TOP")
		(4 "In1.Cu" signal "GND")
		(6 "In2.Cu" signal "IN1")
		(8 "In3.Cu" signal "GND1")
		(10 "In4.Cu" signal "IN2")
		(12 "In5.Cu" signal "GND2")
		(14 "In6.Cu" signal "IN3")
		(16 "In7.Cu" signal "GND3")
		(18 "In8.Cu" signal "VCC")
		(20 "In9.Cu" signal "VCC1")
		(22 "In10.Cu" signal "GND4")
		(24 "In11.Cu" signal "IN4")
		(26 "In12.Cu" signal "GND5")
		(28 "In13.Cu" signal "IN5")
		(30 "In14.Cu" signal "GND6")
		(32 "In15.Cu" signal "IN6")
		(34 "In16.Cu" signal "GND7")
		(2 "B.Cu" signal "BOTTOM")
		(9 "F.Adhes" user "F.Adhesive")
		(11 "B.Adhes" user "B.Adhesive")
		(13 "F.Paste" user "Package Geometry/Pastemask Top")
		(15 "B.Paste" user "Package Geometry/Pastemask Bottom")
		(5 "F.SilkS" user "Ref Des/Silkscreen Top")
		(7 "B.SilkS" user "Ref Des/Silkscreen Bottom")
		(1 "F.Mask" user "Board Geometry/Soldermask Top")
		(3 "B.Mask" user "Board Geometry/Soldermask Bottom")
		(17 "Dwgs.User" user "User.Drawings")
		(19 "Cmts.User" user "User.Comments")
		(21 "Eco1.User" user "User.Eco1")
		(23 "Eco2.User" user "User.Eco2")
		(25 "Edge.Cuts" user "Board Geometry/Outline")
		(27 "Margin" user)
		(31 "F.CrtYd" user "Package Geometry/Place Bound Top")
		(29 "B.CrtYd" user "Package Geometry/Place Bound Bottom")
		(35 "F.Fab" user "Ref Des/Assembly Top")
		(33 "B.Fab" user "Ref Des/Assembly Bottom")
	)
	(footprint ""
		(layer "B.Cu")
		(at 160.83788 -118.836948)
		(property "Reference" "R986"
			(at 0 0 0)
			(layer "B.SilkS")
			(hide yes)
			(effects
				(font
					(size 1.27 1.27)
				)
				(justify mirror)
			)
		)
		(property "Value" ""
			(at 0 0 0)
			(layer "B.Fab")
			(effects
				(font
					(size 1.27 1.27)
				)
				(justify mirror)
			)
		)
		(duplicate_pad_numbers_are_jumpers no)
		(fp_line
			(start -0.7874 -0.4064)
			(end -0.7874 0.4064)
			(stroke
				(width 0.1524)
				(type default)
			)
			(layer "B.SilkS")
		)
		(fp_line
			(start -0.7874 0.4064)
			(end 0.7874 0.4064)
			(stroke
				(width 0.1524)
				(type default)
			)
			(layer "B.SilkS")
		)
		(fp_line
			(start 0.7874 -0.4064)
			(end -0.7874 -0.4064)
			(stroke
				(width 0.1524)
				(type default)
			)
			(layer "B.SilkS")
		)
		(fp_line
			(start 0.7874 0.4064)
			(end 0.7874 -0.4064)
			(stroke
				(width 0.1524)
				(type default)
			)
			(layer "B.SilkS")
		)
		(fp_line
			(start -0.67945 -0.3048)
			(end -0.67945 0.3048)
			(stroke
				(width 0.1)
				(type default)
			)
			(layer "B.Fab")
		)
		(fp_line
			(start -0.67945 0.3048)
			(end -0.120396 0.3048)
			(stroke
				(width 0.1)
				(type default)
			)
			(layer "B.Fab")
		)
		(fp_line
			(start -0.12065 -0.3048)
			(end -0.67945 -0.3048)
			(stroke
				(width 0.1)
				(type default)
			)
			(layer "B.Fab")
		)
		(fp_line
			(start -0.12065 -0.2794)
			(end -0.12065 -0.3048)
			(stroke
				(width 0.1)
				(type default)
			)
			(layer "B.Fab")
		)
		(fp_line
			(start -0.120396 0.2794)
			(end 0.12065 0.2794)
			(stroke
				(width 0.1)
				(type default)
			)
			(layer "B.Fab")
		)
		(fp_line
			(start -0.120396 0.3048)
			(end -0.120396 0.2794)
			(stroke
				(width 0.1)
				(type default)
			)
			(layer "B.Fab")
		)
		(fp_line
			(start 0.12065 -0.305054)
			(end 0.12065 -0.2794)
			(stroke
				(width 0.1)
				(type default)
			)
			(layer "B.Fab")
		)
		(fp_line
			(start 0.12065 -0.2794)
			(end -0.12065 -0.2794)
			(stroke
				(width 0.1)
				(type default)
			)
			(layer "B.Fab")
		)
		(fp_line
			(start 0.12065 0.2794)
			(end 0.12065 0.3048)
			(stroke
				(width 0.1)
				(type default)
			)
			(layer "B.Fab")
		)
		(fp_line
			(start 0.12065 0.3048)
			(end 0.67945 0.3048)
			(stroke
				(width 0.1)
				(type default)
			)
			(layer "B.Fab")
		)
		(fp_line
			(start 0.67945 -0.305054)
			(end 0.12065 -0.305054)
			(stroke
				(width 0.1)
				(type default)
			)
			(layer "B.Fab")
		)
		(fp_line
			(start 0.67945 0.3048)
			(end 0.67945 -0.305054)
			(stroke
				(width 0.1)
				(type default)
			)
			(layer "B.Fab")
		)
		(pad "1" smd circle
			(at 0.40005 0 180)
			(size 0 0)
			(layers "B.Cu" "B.Mask" "B.Paste")
			(net "FM_PVCCFA_EHV_CPU1_R_EN")
		)
		(pad "2" smd circle
			(at -0.40005 0 180)
			(size 0 0)
			(layers "B.Cu" "B.Mask" "B.Paste")
			(net "FM_PVCCFA_EHV_CPU1_EN")
		)
	)
	(footprint ""
		(layer "B.Cu")
		(at 57.429146 -319.41008 180)
		(property "Reference" "R893"
			(at 0 0 0)
			(layer "B.SilkS")
			(hide yes)
			(effects
				(font
					(size 1.27 1.27)
				)
				(justify mirror)
			)
		)
		(property "Value" ""
			(at 0 0 0)
			(layer "B.Fab")
			(effects
				(font
					(size 1.27 1.27)
				)
				(justify mirror)
			)
		)
		(duplicate_pad_numbers_are_jumpers no)
		(fp_line
			(start 0.7874 0.4064)
			(end 0.7874 -0.4064)
			(stroke
				(width 0.1524)
				(type default)
			)
			(layer "B.SilkS")
		)
		(fp_line
			(start 0.7874 -0.4064)
			(end -0.7874 -0.4064)
			(stroke
				(width 0.1524)
				(type default)
			)
			(layer "B.SilkS")
		)
		(fp_line
			(start -0.7874 0.4064)
			(end 0.7874 0.4064)
			(stroke
				(width 0.1524)
				(type default)
			)
			(layer "B.SilkS")
		)
		(fp_line
			(start -0.7874 -0.4064)
			(end -0.7874 0.4064)
			(stroke
				(width 0.1524)
				(type default)
			)
			(layer "B.SilkS")
		)
		(fp_line
			(start 0.67945 0.3048)
			(end 0.67945 -0.305054)
			(stroke
				(width 0.1)
				(type default)
			)
			(layer "B.Fab")
		)
		(fp_line
			(start 0.67945 -0.305054)
			(end 0.12065 -0.305054)
			(stroke
				(width 0.1)
				(type default)
			)
			(layer "B.Fab")
		)
		(fp_line
			(start 0.12065 0.3048)
			(end 0.67945 0.3048)
			(stroke
				(width 0.1)
				(type default)
			)
			(layer "B.Fab")
		)
		(fp_line
			(start 0.12065 0.2794)
			(end 0.12065 0.3048)
			(stroke
				(width 0.1)
				(type default)
			)
			(layer "B.Fab")
		)
		(fp_line
			(start 0.12065 -0.2794)
			(end -0.12065 -0.2794)
			(stroke
				(width 0.1)
				(type default)
			)
			(layer "B.Fab")
		)
		(fp_line
			(start 0.12065 -0.305054)
			(end 0.12065 -0.2794)
			(stroke
				(width 0.1)
				(type default)
			)
			(layer "B.Fab")
		)
		(fp_line
			(start -0.120396 0.3048)
			(end -0.120396 0.2794)
			(stroke
				(width 0.1)
				(type default)
			)
			(layer "B.Fab")
		)
		(fp_line
			(start -0.120396 0.2794)
			(end 0.12065 0.2794)
			(stroke
				(width 0.1)
				(type default)
			)
			(layer "B.Fab")
		)
		(fp_line
			(start -0.12065 -0.2794)
			(end -0.12065 -0.3048)
			(stroke
				(width 0.1)
				(type default)
			)
			(layer "B.Fab")
		)
		(fp_line
			(start -0.12065 -0.3048)
			(end -0.67945 -0.3048)
			(stroke
				(width 0.1)
				(type default)
			)
			(layer "B.Fab")
		)
		(fp_line
			(start -0.67945 0.3048)
			(end -0.120396 0.3048)
			(stroke
				(width 0.1)
				(type default)
			)
			(layer "B.Fab")
		)
		(fp_line
			(start -0.67945 -0.3048)
			(end -0.67945 0.3048)
			(stroke
				(width 0.1)
				(type default)
			)
			(layer "B.Fab")
		)
		(pad "1" smd circle
			(at 0.40005 0)
			(size 0 0)
			(layers "B.Cu" "B.Mask" "B.Paste")
			(net "PWRGD_CHA_CPU1_DIMM1")
		)
		(pad "2" smd circle
			(at -0.40005 0)
			(size 0 0)
			(layers "B.Cu" "B.Mask" "B.Paste")
			(net "PWRGD_FAIL_CPU1_AB")
		)
	)
)
